(kicad_pcb
	(version 20260206)
	(generator "pcbnew")
	(generator_version "10.0")
	(general
		(thickness 1.6)
		(legacy_teardrops no)
	)
	(paper "A4")
	(title_block
		(title "03242023_DA0F0TMBIJ0_F0T_Motherboard_J_brd_V01_OCP.brd")
		(comment 1 "Grand Teton / footprints 2435-2439 of 6105")
	)
	(layers
		(0 "F.Cu" signal "TOP")
		(4 "In1.Cu" signal "GND")
		(6 "In2.Cu" signal "IN1")
		(8 "In3.Cu" signal "GND1")
		(10 "In4.Cu" signal "IN2")
		(12 "In5.Cu" signal "GND2")
		(14 "In6.Cu" signal "IN3")
		(16 "In7.Cu" signal "GND3")
		(18 "In8.Cu" signal "VCC")
		(20 "In9.Cu" signal "VCC1")
		(22 "In10.Cu" signal "GND4")
		(24 "In11.Cu" signal "IN4")
		(26 "In12.Cu" signal "GND5")
		(28 "In13.Cu" signal "IN5")
		(30 "In14.Cu" signal "GND6")
		(32 "In15.Cu" signal "IN6")
		(34 "In16.Cu" signal "GND7")
		(2 "B.Cu" signal "BOTTOM")
		(9 "F.Adhes" user "F.Adhesive")
		(11 "B.Adhes" user "B.Adhesive")
		(13 "F.Paste" user "Package Geometry/Pastemask Top")
		(15 "B.Paste" user "Package Geometry/Pastemask Bottom")
		(5 "F.SilkS" user "Ref Des/Silkscreen Top")
		(7 "B.SilkS" user "Ref Des/Silkscreen Bottom")
		(1 "F.Mask" user "Board Geometry/Soldermask Top")
		(3 "B.Mask" user "Board Geometry/Soldermask Bottom")
		(17 "Dwgs.User" user "User.Drawings")
		(19 "Cmts.User" user "User.Comments")
		(21 "Eco1.User" user "User.Eco1")
		(23 "Eco2.User" user "User.Eco2")
		(25 "Edge.Cuts" user "Board Geometry/Outline")
		(27 "Margin" user)
		(31 "F.CrtYd" user "Package Geometry/Place Bound Top")
		(29 "B.CrtYd" user "Package Geometry/Place Bound Bottom")
		(35 "F.Fab" user "Ref Des/Assembly Top")
		(33 "B.Fab" user "Ref Des/Assembly Bottom")
	)
	(footprint ""
		(layer "F.Cu")
		(at 221.508066 -402.722842 180)
		(property "Reference" "PU296"
			(at -0.222504 7.882128 0)
			(unlocked yes)
			(layer "F.SilkS")
			(effects
				(font
					(size 0.7874 0.5842)
					(thickness 0.1524)
				)
			)
		)
		(property "Value" ""
			(at 0 0 180)
			(layer "F.Fab")
			(effects
				(font
					(size 1.27 1.27)
				)
			)
		)
		(duplicate_pad_numbers_are_jumpers no)
		(fp_line
			(start 2.567686 2.567686)
			(end 2.567686 -2.567686)
			(stroke
				(width 0.1524)
				(type default)
			)
			(layer "F.SilkS")
		)
		(fp_line
			(start 2.567686 -2.567686)
			(end -2.567686 -2.567686)
			(stroke
				(width 0.1524)
				(type default)
			)
			(layer "F.SilkS")
		)
		(fp_line
			(start -2.567686 2.567686)
			(end 2.567686 2.567686)
			(stroke
				(width 0.1524)
				(type default)
			)
			(layer "F.SilkS")
		)
		(fp_line
			(start -2.567686 -2.567686)
			(end -2.567686 2.567686)
			(stroke
				(width 0.1524)
				(type default)
			)
			(layer "F.SilkS")
		)
		(fp_poly
			(pts
				(xy -3.1242 -3.37058) (xy -2.765044 -2.292858) (xy -3.842766 -2.652014)
			)
			(stroke
				(width 0)
				(type default)
			)
			(fill yes)
			(layer "F.SilkS")
		)
		(fp_line
			(start 2.549906 2.549906)
			(end 2.549906 -2.549906)
			(stroke
				(width 0.1)
				(type default)
			)
			(layer "F.Fab")
		)
		(fp_line
			(start 2.549906 -2.549906)
			(end -2.549906 -2.549906)
			(stroke
				(width 0.1)
				(type default)
			)
			(layer "F.Fab")
		)
		(fp_line
			(start -2.549906 2.549906)
			(end 2.549906 2.549906)
			(stroke
				(width 0.1)
				(type default)
			)
			(layer "F.Fab")
		)
		(fp_line
			(start -2.549906 -2.549906)
			(end -2.549906 2.549906)
			(stroke
				(width 0.1)
				(type default)
			)
			(layer "F.Fab")
		)
		(fp_poly
			(pts
				(xy -3.806698 -2.25806) (xy -3.806698 -1.24206) (xy -2.790698 -1.75006)
			)
			(stroke
				(width 0)
				(type default)
			)
			(fill yes)
			(layer "F.Fab")
		)
		(pad "1" smd rect
			(at -2.250186 -1.75006 270)
			(size 0.254 0.3556)
			(layers "F.Cu" "F.Mask" "F.Paste")
			(net "P12V_AUX")
		)
		(pad "2" smd rect
			(at -2.237486 -1.249934 270)
			(size 0.254 0.381)
			(layers "F.Cu" "F.Mask" "F.Paste")
			(net "P12V_AUX")
		)
		(pad "3" smd rect
			(at -2.237486 -0.750062 270)
			(size 0.254 0.381)
			(layers "F.Cu" "F.Mask" "F.Paste")
			(net "HSC_D_OC_3")
		)
		(pad "4" smd rect
			(at -2.237486 -0.249936 270)
			(size 0.254 0.381)
			(layers "F.Cu" "F.Mask" "F.Paste")
			(net "HSC_ON")
		)
		(pad "5" smd rect
			(at -2.237486 0.249936 270)
			(size 0.254 0.381)
			(layers "F.Cu" "F.Mask" "F.Paste")
			(net "HSC_FAULT")
		)
		(pad "6" smd rect
			(at -2.237486 0.750062 270)
			(size 0.254 0.381)
			(layers "F.Cu" "F.Mask" "F.Paste")
			(net "HSC_FLT_TYPE_3")
		)
		(pad "7" smd rect
			(at -2.237486 1.249934 270)
			(size 0.254 0.381)
			(layers "F.Cu" "F.Mask" "F.Paste")
			(net "HSC_NC1_3")
		)
		(pad "8" smd rect
			(at -2.250186 1.75006 270)
			(size 0.254 0.3556)
			(layers "F.Cu" "F.Mask" "F.Paste")
			(net "HSC_MODE_3")
		)
		(pad "9" smd rect
			(at -1.75006 2.250186 180)
			(size 0.254 0.3556)
			(layers "F.Cu" "F.Mask" "F.Paste")
			(net "P12V_PSU")
		)
		(pad "10" smd rect
			(at -1.249934 2.237486 180)
			(size 0.254 0.381)
			(layers "F.Cu" "F.Mask" "F.Paste")
			(net "P12V_PSU")
		)
		(pad "11" smd rect
			(at -0.750062 2.237486 180)
			(size 0.254 0.381)
			(layers "F.Cu" "F.Mask" "F.Paste")
			(net "P12V_PSU")
		)
		(pad "12" smd rect
			(at -0.249936 2.237486 180)
			(size 0.254 0.381)
			(layers "F.Cu" "F.Mask" "F.Paste")
			(net "P12V_PSU")
		)
		(pad "13" smd rect
			(at 0.249936 2.237486 180)
			(size 0.254 0.381)
			(layers "F.Cu" "F.Mask" "F.Paste")
			(net "P12V_PSU")
		)
		(pad "14" smd rect
			(at 0.750062 2.237486 180)
			(size 0.254 0.381)
			(layers "F.Cu" "F.Mask" "F.Paste")
			(net "P12V_PSU")
		)
		(pad "15" smd rect
			(at 1.249934 2.237486 180)
			(size 0.254 0.381)
			(layers "F.Cu" "F.Mask" "F.Paste")
			(net "P12V_PSU")
		)
		(pad "16" smd rect
			(at 1.75006 2.250186 180)
			(size 0.254 0.3556)
			(layers "F.Cu" "F.Mask" "F.Paste")
			(net "P12V_PSU")
		)
		(pad "17" smd rect
			(at 2.250186 1.75006 270)
			(size 0.254 0.3556)
			(layers "F.Cu" "F.Mask" "F.Paste")
			(net "HSC_SCREF_3")
		)
		(pad "18" smd rect
			(at 2.237486 1.249934 270)
			(size 0.254 0.381)
			(layers "F.Cu" "F.Mask" "F.Paste")
			(net "HSC_VTEMP")
		)
		(pad "19" smd rect
			(at 2.237486 0.750062 270)
			(size 0.254 0.381)
			(layers "F.Cu" "F.Mask" "F.Paste")
			(net "HSC_SS")
		)
		(pad "20" smd rect
			(at 2.237486 0.249936 270)
			(size 0.254 0.381)
			(layers "F.Cu" "F.Mask" "F.Paste")
			(net "AGND_HSC")
		)
		(pad "21" smd rect
			(at 2.237486 -0.249936 270)
			(size 0.254 0.381)
			(layers "F.Cu" "F.Mask" "F.Paste")
			(net "HSC_VDD_R_3")
		)
		(pad "22" smd rect
			(at 2.237486 -0.750062 270)
			(size 0.254 0.381)
			(layers "F.Cu" "F.Mask" "F.Paste")
			(net "HSC_IMON")
		)
		(pad "23" smd rect
			(at 2.237486 -1.249934 270)
			(size 0.254 0.381)
			(layers "F.Cu" "F.Mask" "F.Paste")
			(net "HSC_CS_3")
		)
		(pad "24" smd rect
			(at 2.250186 -1.75006 270)
			(size 0.254 0.3556)
			(layers "F.Cu" "F.Mask" "F.Paste")
			(net "HSC_OCREF")
		)
		(pad "25" smd rect
			(at 1.75006 -2.250186 180)
			(size 0.254 0.3556)
			(layers "F.Cu" "F.Mask" "F.Paste")
			(net "P12V_AUX")
		)
		(pad "26" smd rect
			(at 1.249934 -2.237486 180)
			(size 0.254 0.381)
			(layers "F.Cu" "F.Mask" "F.Paste")
			(net "P12V_AUX")
		)
		(pad "27" smd rect
			(at 0.750062 -2.237486 180)
			(size 0.254 0.381)
			(layers "F.Cu" "F.Mask" "F.Paste")
			(net "P12V_AUX")
		)
		(pad "28" smd rect
			(at 0.249936 -2.237486 180)
			(size 0.254 0.381)
			(layers "F.Cu" "F.Mask" "F.Paste")
			(net "P12V_AUX")
		)
		(pad "29" smd rect
			(at -0.249936 -2.237486 180)
			(size 0.254 0.381)
			(layers "F.Cu" "F.Mask" "F.Paste")
			(net "P12V_AUX")
		)
		(pad "30" smd rect
			(at -0.750062 -2.237486 180)
			(size 0.254 0.381)
			(layers "F.Cu" "F.Mask" "F.Paste")
			(net "P12V_AUX")
		)
		(pad "31" smd rect
			(at -1.249934 -2.237486 180)
			(size 0.254 0.381)
			(layers "F.Cu" "F.Mask" "F.Paste")
			(net "P12V_AUX")
		)
		(pad "32" smd rect
			(at -1.75006 -2.250186 180)
			(size 0.254 0.3556)
			(layers "F.Cu" "F.Mask" "F.Paste")
			(net "P12V_AUX")
		)
		(pad "33" smd rect
			(at 0 0 180)
			(size 3.4036 3.4036)
			(layers "F.Cu" "F.Mask" "F.Paste")
			(net "P12V_PSU")
		)
		(zone
			(layer "F.Cu")
			(hatch none 0.5)
			(connect_pads
				(clearance 0)
			)
			(min_thickness 0.25)
			(keepout
				(tracks not_allowed)
				(vias allowed)
				(pads allowed)
				(copperpour not_allowed)
				(footprints allowed)
			)
			(placement
				(enabled no)
				(sheetname "")
			)
			(fill
				(thermal_gap 0.5)
				(thermal_bridge_width 0.5)
				(island_removal_mode 0)
			)
			(polygon
				(pts
					(xy 223.529652 -401.275042) (xy 223.529652 -400.769328) (xy 223.46158 -400.701256) (xy 222.955866 -400.701256)
					(xy 222.955866 -400.726656) (xy 220.060266 -400.726656) (xy 220.060266 -400.701256) (xy 219.48648 -400.701256)
					(xy 219.48648 -401.275042) (xy 219.51188 -401.275042) (xy 219.51188 -404.170642) (xy 219.48648 -404.170642)
					(xy 219.48648 -404.475442) (xy 219.755466 -404.475442) (xy 219.755466 -400.970242) (xy 223.260666 -400.970242)
					(xy 223.260666 -403.230842) (xy 223.504252 -403.230842) (xy 223.504252 -401.275042)
				)
			)
		)
	)
	(footprint ""
		(layer "F.Cu")
		(at 347.057726 -22.36978 90)
		(property "Reference" "R1828"
			(at 0 0 90)
			(layer "F.SilkS")
			(hide yes)
			(effects
				(font
					(size 1.27 1.27)
				)
			)
		)
		(property "Value" ""
			(at 0 0 90)
			(layer "F.Fab")
			(effects
				(font
					(size 1.27 1.27)
				)
			)
		)
		(duplicate_pad_numbers_are_jumpers no)
		(fp_line
			(start 0.7874 -0.4064)
			(end 0.7874 0.4064)
			(stroke
				(width 0.1524)
				(type default)
			)
			(layer "F.SilkS")
		)
		(fp_line
			(start -0.7874 -0.4064)
			(end 0.7874 -0.4064)
			(stroke
				(width 0.1524)
				(type default)
			)
			(layer "F.SilkS")
		)
		(fp_line
			(start 0.7874 0.4064)
			(end -0.7874 0.4064)
			(stroke
				(width 0.1524)
				(type default)
			)
			(layer "F.SilkS")
		)
		(fp_line
			(start -0.7874 0.4064)
			(end -0.7874 -0.4064)
			(stroke
				(width 0.1524)
				(type default)
			)
			(layer "F.SilkS")
		)
		(fp_line
			(start -0.12065 -0.305054)
			(end -0.12065 -0.2794)
			(stroke
				(width 0.1)
				(type default)
			)
			(layer "F.Fab")
		)
		(fp_line
			(start -0.67945 -0.305054)
			(end -0.12065 -0.305054)
			(stroke
				(width 0.1)
				(type default)
			)
			(layer "F.Fab")
		)
		(fp_line
			(start 0.67945 -0.3048)
			(end 0.67945 0.3048)
			(stroke
				(width 0.1)
				(type default)
			)
			(layer "F.Fab")
		)
		(fp_line
			(start 0.12065 -0.3048)
			(end 0.67945 -0.3048)
			(stroke
				(width 0.1)
				(type default)
			)
			(layer "F.Fab")
		)
		(fp_line
			(start 0.12065 -0.2794)
			(end 0.12065 -0.3048)
			(stroke
				(width 0.1)
				(type default)
			)
			(layer "F.Fab")
		)
		(fp_line
			(start -0.12065 -0.2794)
			(end 0.12065 -0.2794)
			(stroke
				(width 0.1)
				(type default)
			)
			(layer "F.Fab")
		)
		(fp_line
			(start 0.120396 0.2794)
			(end -0.12065 0.2794)
			(stroke
				(width 0.1)
				(type default)
			)
			(layer "F.Fab")
		)
		(fp_line
			(start -0.12065 0.2794)
			(end -0.12065 0.3048)
			(stroke
				(width 0.1)
				(type default)
			)
			(layer "F.Fab")
		)
		(fp_line
			(start 0.67945 0.3048)
			(end 0.120396 0.3048)
			(stroke
				(width 0.1)
				(type default)
			)
			(layer "F.Fab")
		)
		(fp_line
			(start 0.120396 0.3048)
			(end 0.120396 0.2794)
			(stroke
				(width 0.1)
				(type default)
			)
			(layer "F.Fab")
		)
		(fp_line
			(start -0.12065 0.3048)
			(end -0.67945 0.3048)
			(stroke
				(width 0.1)
				(type default)
			)
			(layer "F.Fab")
		)
		(fp_line
			(start -0.67945 0.3048)
			(end -0.67945 -0.305054)
			(stroke
				(width 0.1)
				(type default)
			)
			(layer "F.Fab")
		)
		(pad "1" smd circle
			(at -0.40005 0 90)
			(size 0 0)
			(layers "F.Cu" "F.Mask" "F.Paste")
			(net "USB_OC1_REAR_R_N")
		)
		(pad "2" smd circle
			(at 0.40005 0 90)
			(size 0 0)
			(layers "F.Cu" "F.Mask" "F.Paste")
			(net "P3V3_AUX")
		)
	)
	(footprint ""
		(layer "F.Cu")
		(at 46.676818 -105.874058)
		(property "Reference" "L15"
			(at 0 0 0)
			(layer "F.SilkS")
			(hide yes)
			(effects
				(font
					(size 1.27 1.27)
				)
			)
		)
		(property "Value" ""
			(at 0 0 0)
			(layer "F.Fab")
			(effects
				(font
					(size 1.27 1.27)
				)
			)
		)
		(duplicate_pad_numbers_are_jumpers no)
		(fp_line
			(start -1.27 -0.5842)
			(end 1.27 -0.5842)
			(stroke
				(width 0.1524)
				(type default)
			)
			(layer "F.SilkS")
		)
		(fp_line
			(start -1.27 -0.5588)
			(end -1.27 -0.5842)
			(stroke
				(width 0.1524)
				(type default)
			)
			(layer "F.SilkS")
		)
		(fp_line
			(start -1.27 0.5842)
			(end -1.27 -0.5842)
			(stroke
				(width 0.1524)
				(type default)
			)
			(layer "F.SilkS")
		)
		(fp_line
			(start -0.127 0.5842)
			(end -0.127 -0.5842)
			(stroke
				(width 0.1524)
				(type default)
			)
			(layer "F.SilkS")
		)
		(fp_line
			(start 0.127 0.5842)
			(end 0.127 -0.5842)
			(stroke
				(width 0.1524)
				(type default)
			)
			(layer "F.SilkS")
		)
		(fp_line
			(start 1.27 0.5842)
			(end -1.27 0.5842)
			(stroke
				(width 0.1524)
				(type default)
			)
			(layer "F.SilkS")
		)
		(fp_line
			(start 1.27 0.5842)
			(end 1.27 -0.5842)
			(stroke
				(width 0.1524)
				(type default)
			)
			(layer "F.SilkS")
		)
		(fp_line
			(start -1.194308 -0.406654)
			(end -0.9144 -0.406654)
			(stroke
				(width 0.1)
				(type default)
			)
			(layer "F.Fab")
		)
		(fp_line
			(start -1.194308 0.406654)
			(end -1.194308 -0.406654)
			(stroke
				(width 0.1)
				(type default)
			)
			(layer "F.Fab")
		)
		(fp_line
			(start -0.9144 -0.508)
			(end 0.9144 -0.508)
			(stroke
				(width 0.1)
				(type default)
			)
			(layer "F.Fab")
		)
		(fp_line
			(start -0.9144 -0.406654)
			(end -0.9144 -0.508)
			(stroke
				(width 0.1)
				(type default)
			)
			(layer "F.Fab")
		)
		(fp_line
			(start -0.9144 0.406654)
			(end -1.194308 0.406654)
			(stroke
				(width 0.1)
				(type default)
			)
			(layer "F.Fab")
		)
		(fp_line
			(start -0.9144 0.508)
			(end -0.9144 0.406654)
			(stroke
				(width 0.1)
				(type default)
			)
			(layer "F.Fab")
		)
		(fp_line
			(start 0.9144 -0.508)
			(end 0.9144 -0.406654)
			(stroke
				(width 0.1)
				(type default)
			)
			(layer "F.Fab")
		)
		(fp_line
			(start 0.9144 -0.406654)
			(end 1.1938 -0.406654)
			(stroke
				(width 0.1)
				(type default)
			)
			(layer "F.Fab")
		)
		(fp_line
			(start 0.9144 0.4064)
			(end 0.9144 0.508)
			(stroke
				(width 0.1)
				(type default)
			)
			(layer "F.Fab")
		)
		(fp_line
			(start 0.9144 0.508)
			(end -0.9144 0.508)
			(stroke
				(width 0.1)
				(type default)
			)
			(layer "F.Fab")
		)
		(fp_line
			(start 1.1938 -0.406654)
			(end 1.1938 0.4064)
			(stroke
				(width 0.1)
				(type default)
			)
			(layer "F.Fab")
		)
		(fp_line
			(start 1.1938 0.4064)
			(end 0.9144 0.4064)
			(stroke
				(width 0.1)
				(type default)
			)
			(layer "F.Fab")
		)
		(pad "1" smd rect
			(at -0.7366 0 270)
			(size 0.7112 0.8128)
			(layers "F.Cu" "F.Mask" "F.Paste")
			(net "P3V3_MAX11617_VDD")
		)
		(pad "2" smd rect
			(at 0.7366 0 270)
			(size 0.7112 0.8128)
			(layers "F.Cu" "F.Mask" "F.Paste")
			(net "P3V3_AUX")
		)
	)
	(footprint ""
		(layer "F.Cu")
		(at 107.96905 -29.842714)
		(property "Reference" "C1859"
			(at 0 0 0)
			(layer "F.SilkS")
			(hide yes)
			(effects
				(font
					(size 1.27 1.27)
				)
			)
		)
		(property "Value" ""
			(at 0 0 0)
			(layer "F.Fab")
			(effects
				(font
					(size 1.27 1.27)
				)
			)
		)
		(duplicate_pad_numbers_are_jumpers no)
		(fp_line
			(start -0.7874 -0.4064)
			(end 0.7874 -0.4064)
			(stroke
				(width 0.1524)
				(type default)
			)
			(layer "F.SilkS")
		)
		(fp_line
			(start -0.7874 0.4064)
			(end -0.7874 -0.4064)
			(stroke
				(width 0.1524)
				(type default)
			)
			(layer "F.SilkS")
		)
		(fp_line
			(start 0.7874 -0.4064)
			(end 0.7874 0.4064)
			(stroke
				(width 0.1524)
				(type default)
			)
			(layer "F.SilkS")
		)
		(fp_line
			(start 0.7874 0.4064)
			(end -0.7874 0.4064)
			(stroke
				(width 0.1524)
				(type default)
			)
			(layer "F.SilkS")
		)
		(fp_line
			(start -0.67945 -0.305054)
			(end -0.12065 -0.305054)
			(stroke
				(width 0.1)
				(type default)
			)
			(layer "F.Fab")
		)
		(fp_line
			(start -0.67945 0.3048)
			(end -0.67945 -0.305054)
			(stroke
				(width 0.1)
				(type default)
			)
			(layer "F.Fab")
		)
		(fp_line
			(start -0.12065 -0.305054)
			(end -0.12065 -0.2794)
			(stroke
				(width 0.1)
				(type default)
			)
			(layer "F.Fab")
		)
		(fp_line
			(start -0.12065 -0.2794)
			(end 0.12065 -0.2794)
			(stroke
				(width 0.1)
				(type default)
			)
			(layer "F.Fab")
		)
		(fp_line
			(start -0.12065 0.2794)
			(end -0.12065 0.3048)
			(stroke
				(width 0.1)
				(type default)
			)
			(layer "F.Fab")
		)
		(fp_line
			(start -0.12065 0.3048)
			(end -0.67945 0.3048)
			(stroke
				(width 0.1)
				(type default)
			)
			(layer "F.Fab")
		)
		(fp_line
			(start 0.120396 0.2794)
			(end -0.12065 0.2794)
			(stroke
				(width 0.1)
				(type default)
			)
			(layer "F.Fab")
		)
		(fp_line
			(start 0.120396 0.3048)
			(end 0.120396 0.2794)
			(stroke
				(width 0.1)
				(type default)
			)
			(layer "F.Fab")
		)
		(fp_line
			(start 0.12065 -0.3048)
			(end 0.67945 -0.3048)
			(stroke
				(width 0.1)
				(type default)
			)
			(layer "F.Fab")
		)
		(fp_line
			(start 0.12065 -0.2794)
			(end 0.12065 -0.3048)
			(stroke
				(width 0.1)
				(type default)
			)
			(layer "F.Fab")
		)
		(fp_line
			(start 0.67945 -0.3048)
			(end 0.67945 0.3048)
			(stroke
				(width 0.1)
				(type default)
			)
			(layer "F.Fab")
		)
		(fp_line
			(start 0.67945 0.3048)
			(end 0.120396 0.3048)
			(stroke
				(width 0.1)
				(type default)
			)
			(layer "F.Fab")
		)
		(pad "1" smd circle
			(at -0.40005 0)
			(size 0 0)
			(layers "F.Cu" "F.Mask" "F.Paste")
			(net "P3V3_AUX")
		)
		(pad "2" smd circle
			(at 0.40005 0)
			(size 0 0)
			(layers "F.Cu" "F.Mask" "F.Paste")
			(net "GND")
		)
	)
	(footprint ""
		(layer "F.Cu")
		(at 424.7642 -16.088614 90)
		(property "Reference" "C862"
			(at 0 0 90)
			(layer "F.SilkS")
			(hide yes)
			(effects
				(font
					(size 1.27 1.27)
				)
			)
		)
		(property "Value" ""
			(at 0 0 90)
			(layer "F.Fab")
			(effects
				(font
					(size 1.27 1.27)
				)
			)
		)
		(duplicate_pad_numbers_are_jumpers no)
		(fp_line
			(start 0.299974 -0.150114)
			(end 0.299974 0.150114)
			(stroke
				(width 0.1)
				(type default)
			)
			(layer "F.Fab")
		)
		(fp_line
			(start -0.299974 -0.150114)
			(end 0.299974 -0.150114)
			(stroke
				(width 0.1)
				(type default)
			)
			(layer "F.Fab")
		)
		(fp_line
			(start 0.299974 0.150114)
			(end -0.299974 0.150114)
			(stroke
				(width 0.1)
				(type default)
			)
			(layer "F.Fab")
		)
		(fp_line
			(start -0.299974 0.150114)
			(end -0.299974 -0.150114)
			(stroke
				(width 0.1)
				(type default)
			)
			(layer "F.Fab")
		)
		(pad "1" smd rect
			(at -0.2667 0 90)
			(size 0.3048 0.381)
			(layers "F.Cu" "F.Mask" "F.Paste")
			(net "P5E_CPU0_PE1_TX_C_DN<3>")
		)
		(pad "2" smd rect
			(at 0.2667 0 90)
			(size 0.3048 0.381)
			(layers "F.Cu" "F.Mask" "F.Paste")
			(net "P5E_CPU0_PE1_TX_DN<3>")
		)
	)
)
